FILE_TYPE = MACRO_DRAWING;
SET COLOR_WIRE YELLOW;
SET COLOR_PROP MONO;
SET COLOR_DOT WHITE;
SET COLOR_ARC YELLOW;
SET COLOR_BODY GREEN;
SET COLOR_NOTE MONO;
SET PROP_DISPLAY VALUE;
SET PAGE_NUMBER P248;
FORCEADD OFFPAGE..2
(-2325 1625);
FORCEPROP 2 LAST $XR0 185 
J 0
(-2136 1625);
DISPLAY 0.638298 (-2136 1625);
PAINT MONO (-2136 1625);
FORCEPROP 1 LAST OFFPAGE TRUE
J 0
(-2000 1500);
DISPLAY 0.872340 (-2000 1500);
PAINT GREEN (-2000 1500);
DISPLAY INVISIBLE (-2000 1500);
FORCEPROP 1 LAST COMMENT_BODY TRUE
J 0
(-2370 1530);
DISPLAY 0.872340 (-2370 1530);
PAINT GREEN (-2370 1530);
DISPLAY INVISIBLE (-2370 1530);
FORCEPROP 2 LAST PATH I10
J 0
(-2150 1700);
DISPLAY 1.021277 (-2150 1700);
PAINT ORANGE (-2150 1700);
DISPLAY INVISIBLE (-2150 1700);
FORCEPROP 2 LAST CDS_LIB mstr_standard
J 0
(-2325 1625);
PAINT MONO (-2325 1625);
DISPLAY INVISIBLE (-2325 1625);
FORCEADD TTL1G08..1
(-3175 1625);
FORCEPROP 2 LASTPIN (-3325 1575) $PN 2
J 2
(-3335 1585);
DISPLAY 0.808511 (-3335 1585);
PAINT ORANGE (-3335 1585);
FORCEPROP 1 LAST LOCATION U14E2
J 0
(-3250 1875);
DISPLAY 0.617021 (-3250 1875);
PAINT AQUA (-3250 1875);
FORCEPROP 1 LAST MATERIAL IC
J 1
(-3200 1835);
DISPLAY 0.617021 (-3200 1835);
PAINT SKYBLUE (-3200 1835);
FORCEPROP 1 LAST PACK_TYPE SOTLF
J 1
(-3200 1800);
DISPLAY 0.617021 (-3200 1800);
PAINT SKYBLUE (-3200 1800);
FORCEPROP 1 LAST PART_NUMBER D10321-001
J 1
(-3200 1725);
DISPLAY 0.617021 (-3200 1725);
PAINT BLUE (-3200 1725);
FORCEPROP 2 LASTPIN (-3025 1625) $PN 4
J 0
(-3015 1635);
DISPLAY 0.808511 (-3015 1635);
PAINT ORANGE (-3015 1635);
FORCEPROP 2 LASTPIN (-3325 1675) $PN 1
J 2
(-3335 1685);
DISPLAY 0.808511 (-3335 1685);
PAINT ORANGE (-3335 1685);
FORCEPROP 1 LAST POWER_GROUP VCC=P3V3;GND=GND;
J 1
(-3150 1450);
DISPLAY 0.617021 (-3150 1450);
PAINT ORANGE (-3150 1450);
FORCEPROP 1 LAST VALUE NC7SZ08
J 1
(-3175 1500);
DISPLAY 0.617021 (-3175 1500);
PAINT SKYBLUE (-3175 1500);
FORCEPROP 0 LAST ROOM MIO_CHASSIS
J 0
(-3275 1950);
DISPLAY 1.021277 (-3275 1950);
PAINT ORANGE (-3275 1950);
DISPLAY INVISIBLE (-3275 1950);
FORCEPROP 0 LAST BOM_COST MIO_CHASSIS
J 0
(-3275 2050);
DISPLAY 1.021277 (-3275 2050);
PAINT ORANGE (-3275 2050);
DISPLAY INVISIBLE (-3275 2050);
FORCEPROP 1 LAST PATH I11
J 1
(-3195 1890);
DISPLAY 0.702128 (-3195 1890);
PAINT WHITE (-3195 1890);
DISPLAY INVISIBLE (-3195 1890);
FORCEPROP 2 LAST CDS_LIB mstr_ttl
J 0
(-3175 1625);
PAINT MONO (-3175 1625);
DISPLAY INVISIBLE (-3175 1625);
FORCEPROP 2 LAST SEC 1
J 0
(-3175 1925);
DISPLAY 0.680851 (-3175 1925);
PAINT MONO (-3175 1925);
DISPLAY INVISIBLE (-3175 1925);
FORCEPROP 2 LAST SEC_TYPE SOTLF
J 0
(-3175 1925);
DISPLAY 1.021277 (-3175 1925);
PAINT ORANGE (-3175 1925);
DISPLAY INVISIBLE (-3175 1925);
FORCEADD OFFPAGE..1
(-3950 1675);
FORCEPROP 2 LAST $XR0 190 
J 0
(-4202 1675);
DISPLAY 0.638298 (-4202 1675);
PAINT MONO (-4202 1675);
FORCEPROP 2 LAST CDS_LIB mstr_standard
J 0
(-3950 1675);
PAINT MONO (-3950 1675);
DISPLAY INVISIBLE (-3950 1675);
FORCEPROP 2 LAST PATH I12
J 0
(-3900 1750);
DISPLAY 1.021277 (-3900 1750);
PAINT ORANGE (-3900 1750);
DISPLAY INVISIBLE (-3900 1750);
FORCEPROP 1 LAST OFFPAGE TRUE
J 0
(-3625 1550);
DISPLAY 0.872340 (-3625 1550);
PAINT GREEN (-3625 1550);
DISPLAY INVISIBLE (-3625 1550);
FORCEPROP 1 LAST COMMENT_BODY TRUE
J 0
(-3825 1575);
DISPLAY 0.872340 (-3825 1575);
PAINT GREEN (-3825 1575);
DISPLAY INVISIBLE (-3825 1575);
FORCEADD CAP_A..1
(-2750 2025);
FORCEPROP 1 LASTPIN (-2750 1925) $PN 2
J 0
(-2740 1905);
DISPLAY 0.617021 (-2740 1905);
PAINT ORANGE (-2740 1905);
FORCEPROP 1 LAST MATERIAL X7R
J 0
(-2700 1925);
DISPLAY 0.617021 (-2700 1925);
PAINT SKYBLUE (-2700 1925);
FORCEPROP 1 LAST TOLERANCE 10%
J 0
(-2700 1975);
DISPLAY 0.617021 (-2700 1975);
PAINT SKYBLUE (-2700 1975);
FORCEPROP 1 LAST VOLTAGE 16V
J 0
(-2700 2025);
DISPLAY 0.617021 (-2700 2025);
PAINT SKYBLUE (-2700 2025);
FORCEPROP 1 LAST LOCATION C14W1
J 0
(-2700 2125);
DISPLAY 0.617021 (-2700 2125);
PAINT AQUA (-2700 2125);
FORCEPROP 1 LAST PART_NUMBER A36096-030
J 0
(-2700 1875);
DISPLAY 0.617021 (-2700 1875);
PAINT BLUE (-2700 1875);
FORCEPROP 1 LASTPIN (-2750 2125) $PN 1
J 0
(-2740 2105);
DISPLAY 0.617021 (-2740 2105);
PAINT ORANGE (-2740 2105);
FORCEPROP 1 LAST VALUE 0.1UF
J 0
(-2700 2075);
DISPLAY 0.617021 (-2700 2075);
PAINT SKYBLUE (-2700 2075);
FORCEPROP 1 LAST PACK_TYPE 0402V
J 0
(-2700 1825);
DISPLAY 0.617021 (-2700 1825);
PAINT SKYBLUE (-2700 1825);
FORCEPROP 1 LAST PATH I13
J 0
(-2700 2175);
DISPLAY 0.978723 (-2700 2175);
PAINT WHITE (-2700 2175);
DISPLAY INVISIBLE (-2700 2175);
FORCEPROP 2 LAST CDS_LIB dev_discrete
J 0
(-2750 2025);
PAINT ORANGE (-2750 2025);
DISPLAY INVISIBLE (-2750 2025);
FORCEPROP 2 LAST CDS_SEC 1
J 0
(-2700 2175);
PAINT ORANGE (-2700 2175);
DISPLAY INVISIBLE (-2700 2175);
FORCEPROP 2 LAST ROOM CPUFANS
J 0
(-2700 2175);
DISPLAY 1.021277 (-2700 2175);
PAINT ORANGE (-2700 2175);
DISPLAY INVISIBLE (-2700 2175);
FORCEPROP 2 LAST SEC 1
J 0
(-2700 2225);
DISPLAY 0.680851 (-2700 2225);
PAINT MONO (-2700 2225);
DISPLAY INVISIBLE (-2700 2225);
FORCEPROP 2 LAST SEC_TYPE 0402V
J 0
(-2700 2225);
DISPLAY 1.021277 (-2700 2225);
PAINT ORANGE (-2700 2225);
DISPLAY INVISIBLE (-2700 2225);
FORCEPROP 2 LAST BOM_COST SM_THERM
J 0
(-2700 2225);
DISPLAY 1.021277 (-2700 2225);
PAINT ORANGE (-2700 2225);
DISPLAY INVISIBLE (-2700 2225);
FORCEPROP 2 LAST CDS_LOCATION C14W1
J 0
(-2700 2125);
DISPLAY 0.617021 (-2700 2125);
PAINT AQUA (-2700 2125);
DISPLAY INVISIBLE (-2700 2125);
FORCEADD GND..1
(-2750 1825);
FORCEPROP 3 LASTPIN (-2750 1875) SIG_NAME GND\g
J 0
(-2740 1885);
DISPLAY 0.659574 (-2740 1885);
PAINT MONO (-2740 1885);
DISPLAY INVISIBLE (-2740 1885);
FORCEPROP 1 LAST PATH I15
J 0
(-2675 1825);
DISPLAY 0.872340 (-2675 1825);
PAINT AQUA (-2675 1825);
DISPLAY INVISIBLE (-2675 1825);
FORCEPROP 1 LAST VOLTAGE 0.0V
J 0
(-2795 1782);
DISPLAY 0.340426 (-2795 1782);
PAINT SKYBLUE (-2795 1782);
DISPLAY INVISIBLE (-2795 1782);
FORCEPROP 2 LAST CDS_LIB mstr_symbols
J 0
(-2750 1825);
PAINT ORANGE (-2750 1825);
DISPLAY INVISIBLE (-2750 1825);
FORCEPROP 1 LAST SIZE 1B
J 0
(-2675 1775);
DISPLAY 1.170213 (-2675 1775);
PAINT AQUA (-2675 1775);
DISPLAY INVISIBLE (-2675 1775);
FORCEPROP 1 LAST BODY_TYPE PLUMBING
J 0
(-2795 1782);
DISPLAY 0.340426 (-2795 1782);
PAINT GREEN (-2795 1782);
DISPLAY INVISIBLE (-2795 1782);
FORCEPROP 1 LAST HDL_POWER GND
J 0
(-2750 1975);
DISPLAY 1.170213 (-2750 1975);
PAINT GREEN (-2750 1975);
DISPLAY INVISIBLE (-2750 1975);
FORCEADD P3V3..1
(-2750 2225);
FORCEPROP 3 LASTPIN (-2750 2175) SIG_NAME P3V3\g
J 0
(-2740 2185);
DISPLAY 0.659574 (-2740 2185);
PAINT MONO (-2740 2185);
DISPLAY INVISIBLE (-2740 2185);
FORCEPROP 1 LAST VOLTAGE 3.3V
J 0
(-2795 2182);
DISPLAY 0.340426 (-2795 2182);
PAINT SKYBLUE (-2795 2182);
DISPLAY INVISIBLE (-2795 2182);
FORCEPROP 1 LAST SIZE 1B
J 0
(-2705 2247);
DISPLAY 0.340426 (-2705 2247);
PAINT GREEN (-2705 2247);
DISPLAY INVISIBLE (-2705 2247);
FORCEPROP 1 LAST BODY_TYPE PLUMBING
J 0
(-2795 2182);
DISPLAY 0.340426 (-2795 2182);
PAINT GREEN (-2795 2182);
DISPLAY INVISIBLE (-2795 2182);
FORCEPROP 1 LAST HDL_POWER P3V3
J 0
(-3075 2100);
DISPLAY 0.872340 (-3075 2100);
PAINT ORANGE (-3075 2100);
DISPLAY INVISIBLE (-3075 2100);
FORCEPROP 1 LAST PATH I16
J 0
(-2705 2227);
DISPLAY 0.340426 (-2705 2227);
PAINT GREEN (-2705 2227);
DISPLAY INVISIBLE (-2705 2227);
FORCEPROP 2 LAST CDS_LIB mstr_symbols
J 0
(-2750 2225);
PAINT MONO (-2750 2225);
DISPLAY INVISIBLE (-2750 2225);
FORCEADD CAP_A..1
(-3700 1175);
FORCEPROP 1 LASTPIN (-3700 1275) $PN 1
J 0
(-3690 1255);
DISPLAY 0.617021 (-3690 1255);
PAINT ORANGE (-3690 1255);
FORCEPROP 1 LAST VALUE 0.1UF
J 0
(-3650 1225);
DISPLAY 0.617021 (-3650 1225);
PAINT SKYBLUE (-3650 1225);
FORCEPROP 1 LAST TOLERANCE 10%
J 0
(-3650 1125);
DISPLAY 0.617021 (-3650 1125);
PAINT SKYBLUE (-3650 1125);
FORCEPROP 1 LAST PART_NUMBER A36096-030
J 0
(-3650 1025);
DISPLAY 0.617021 (-3650 1025);
PAINT BLUE (-3650 1025);
FORCEPROP 1 LAST PACK_TYPE 0402V
J 0
(-3650 975);
DISPLAY 0.617021 (-3650 975);
PAINT SKYBLUE (-3650 975);
FORCEPROP 1 LAST VOLTAGE 16V
J 0
(-3650 1175);
DISPLAY 0.617021 (-3650 1175);
PAINT SKYBLUE (-3650 1175);
FORCEPROP 1 LASTPIN (-3700 1075) $PN 2
J 0
(-3690 1055);
DISPLAY 0.617021 (-3690 1055);
PAINT ORANGE (-3690 1055);
FORCEPROP 1 LAST MATERIAL X7R
J 0
(-3650 1075);
DISPLAY 0.617021 (-3650 1075);
PAINT SKYBLUE (-3650 1075);
FORCEPROP 1 LAST LOCATION C14W2
J 0
(-3650 1275);
DISPLAY 0.617021 (-3650 1275);
PAINT AQUA (-3650 1275);
FORCEPROP 2 LAST BOM_COST SM_THERM
J 0
(-3650 1375);
DISPLAY 1.021277 (-3650 1375);
PAINT ORANGE (-3650 1375);
DISPLAY INVISIBLE (-3650 1375);
FORCEPROP 2 LAST SEC_TYPE 0402V
J 0
(-3650 1375);
DISPLAY 1.021277 (-3650 1375);
PAINT ORANGE (-3650 1375);
DISPLAY INVISIBLE (-3650 1375);
FORCEPROP 2 LAST SEC 1
J 0
(-3650 1375);
DISPLAY 0.680851 (-3650 1375);
PAINT MONO (-3650 1375);
DISPLAY INVISIBLE (-3650 1375);
FORCEPROP 2 LAST ROOM CPUFANS
J 0
(-3650 1325);
DISPLAY 1.021277 (-3650 1325);
PAINT ORANGE (-3650 1325);
DISPLAY INVISIBLE (-3650 1325);
FORCEPROP 2 LAST CDS_SEC 1
J 0
(-3650 1325);
PAINT ORANGE (-3650 1325);
DISPLAY INVISIBLE (-3650 1325);
FORCEPROP 2 LAST CDS_LIB dev_discrete
J 0
(-3700 1175);
PAINT ORANGE (-3700 1175);
DISPLAY INVISIBLE (-3700 1175);
FORCEPROP 1 LAST PATH I17
J 0
(-3650 1325);
DISPLAY 0.978723 (-3650 1325);
PAINT WHITE (-3650 1325);
DISPLAY INVISIBLE (-3650 1325);
FORCEPROP 2 LAST CDS_LOCATION C14W2
J 0
(-3650 1275);
DISPLAY 0.617021 (-3650 1275);
PAINT AQUA (-3650 1275);
DISPLAY INVISIBLE (-3650 1275);
FORCEADD GND..1
(-3700 975);
FORCEPROP 3 LASTPIN (-3700 1025) SIG_NAME GND\g
J 0
(-3690 1035);
DISPLAY 0.659574 (-3690 1035);
PAINT MONO (-3690 1035);
DISPLAY INVISIBLE (-3690 1035);
FORCEPROP 1 LAST HDL_POWER GND
J 0
(-3700 1125);
DISPLAY 1.170213 (-3700 1125);
PAINT GREEN (-3700 1125);
DISPLAY INVISIBLE (-3700 1125);
FORCEPROP 1 LAST BODY_TYPE PLUMBING
J 0
(-3745 932);
DISPLAY 0.340426 (-3745 932);
PAINT GREEN (-3745 932);
DISPLAY INVISIBLE (-3745 932);
FORCEPROP 1 LAST SIZE 1B
J 0
(-3625 925);
DISPLAY 1.170213 (-3625 925);
PAINT AQUA (-3625 925);
DISPLAY INVISIBLE (-3625 925);
FORCEPROP 2 LAST CDS_LIB mstr_symbols
J 0
(-3700 975);
PAINT ORANGE (-3700 975);
DISPLAY INVISIBLE (-3700 975);
FORCEPROP 1 LAST VOLTAGE 0.0V
J 0
(-3745 932);
DISPLAY 0.340426 (-3745 932);
PAINT SKYBLUE (-3745 932);
DISPLAY INVISIBLE (-3745 932);
FORCEPROP 1 LAST PATH I18
J 0
(-3625 975);
DISPLAY 0.872340 (-3625 975);
PAINT AQUA (-3625 975);
DISPLAY INVISIBLE (-3625 975);
FORCEADD TTL1G08..1
(-4050 1275);
FORCEPROP 1 LAST MATERIAL IC
J 1
(-4075 1485);
DISPLAY 0.617021 (-4075 1485);
PAINT SKYBLUE (-4075 1485);
FORCEPROP 1 LAST PACK_TYPE SOTLF
J 1
(-4075 1450);
DISPLAY 0.617021 (-4075 1450);
PAINT SKYBLUE (-4075 1450);
FORCEPROP 1 LAST PART_NUMBER D10321-001
J 1
(-4075 1375);
DISPLAY 0.617021 (-4075 1375);
PAINT BLUE (-4075 1375);
FORCEPROP 1 LAST LOCATION U14E3
J 0
(-4125 1525);
DISPLAY 0.617021 (-4125 1525);
PAINT AQUA (-4125 1525);
FORCEPROP 1 LAST VALUE NC7SZ08
J 1
(-4050 1150);
DISPLAY 0.617021 (-4050 1150);
PAINT SKYBLUE (-4050 1150);
FORCEPROP 1 LAST POWER_GROUP VCC=P3V3;GND=GND;
J 1
(-4025 1100);
DISPLAY 0.617021 (-4025 1100);
PAINT ORANGE (-4025 1100);
FORCEPROP 2 LAST CDS_LIB mstr_ttl
J 0
(-4050 1275);
PAINT MONO (-4050 1275);
DISPLAY INVISIBLE (-4050 1275);
FORCEPROP 1 LAST PATH I19
J 1
(-4070 1540);
DISPLAY 0.702128 (-4070 1540);
PAINT WHITE (-4070 1540);
DISPLAY INVISIBLE (-4070 1540);
FORCEPROP 0 LAST BOM_COST MIO_CHASSIS
J 0
(-4150 1700);
DISPLAY 1.021277 (-4150 1700);
PAINT ORANGE (-4150 1700);
DISPLAY INVISIBLE (-4150 1700);
FORCEPROP 0 LAST ROOM MIO_CHASSIS
J 0
(-4150 1600);
DISPLAY 1.021277 (-4150 1600);
PAINT ORANGE (-4150 1600);
DISPLAY INVISIBLE (-4150 1600);
FORCEADD OFFPAGE..1
(-5250 1325);
FORCEPROP 2 LAST $XR2 241 
J 0
(-5772 1325);
DISPLAY 0.638298 (-5772 1325);
PAINT MONO (-5772 1325);
FORCEPROP 2 LAST $XR1 181 
J 0
(-5652 1325);
DISPLAY 0.638298 (-5652 1325);
PAINT MONO (-5652 1325);
FORCEPROP 2 LAST $XR0 196 
J 0
(-5532 1325);
DISPLAY 0.638298 (-5532 1325);
PAINT MONO (-5532 1325);
FORCEPROP 2 LAST CDS_LIB mstr_standard
J 0
(-5250 1325);
PAINT MONO (-5250 1325);
DISPLAY INVISIBLE (-5250 1325);
FORCEPROP 2 LAST PATH I20
J 0
(-5200 1400);
DISPLAY 1.021277 (-5200 1400);
PAINT ORANGE (-5200 1400);
DISPLAY INVISIBLE (-5200 1400);
FORCEPROP 1 LAST OFFPAGE TRUE
J 0
(-4925 1200);
DISPLAY 0.872340 (-4925 1200);
PAINT GREEN (-4925 1200);
DISPLAY INVISIBLE (-4925 1200);
FORCEPROP 1 LAST COMMENT_BODY TRUE
J 0
(-5125 1225);
DISPLAY 0.872340 (-5125 1225);
PAINT GREEN (-5125 1225);
DISPLAY INVISIBLE (-5125 1225);
FORCEADD OFFPAGE..1
(-5250 1225);
FORCEPROP 2 LAST $XR2 190 
J 0
(-5772 1225);
DISPLAY 0.638298 (-5772 1225);
PAINT MONO (-5772 1225);
FORCEPROP 2 LAST $XR1 175 
J 0
(-5652 1225);
DISPLAY 0.638298 (-5652 1225);
PAINT MONO (-5652 1225);
FORCEPROP 2 LAST $XR0 196 
J 0
(-5532 1225);
DISPLAY 0.638298 (-5532 1225);
PAINT MONO (-5532 1225);
FORCEPROP 1 LAST COMMENT_BODY TRUE
J 0
(-5125 1125);
DISPLAY 0.872340 (-5125 1125);
PAINT GREEN (-5125 1125);
DISPLAY INVISIBLE (-5125 1125);
FORCEPROP 1 LAST OFFPAGE TRUE
J 0
(-4925 1100);
DISPLAY 0.872340 (-4925 1100);
PAINT GREEN (-4925 1100);
DISPLAY INVISIBLE (-4925 1100);
FORCEPROP 2 LAST PATH I21
J 0
(-5200 1300);
DISPLAY 1.021277 (-5200 1300);
PAINT ORANGE (-5200 1300);
DISPLAY INVISIBLE (-5200 1300);
FORCEPROP 2 LAST CDS_LIB mstr_standard
J 0
(-5250 1225);
PAINT MONO (-5250 1225);
DISPLAY INVISIBLE (-5250 1225);
FORCEADD OFFPAGE..3
R 2
(-7200 3475);
FORCEPROP 2 LAST $XR0 21 
J 0
(-7479 3475);
DISPLAY 0.638298 (-7479 3475);
PAINT MONO (-7479 3475);
FORCEPROP 1 LAST COMMENT_BODY TRUE
J 2
(-7150 3375);
DISPLAY 0.872340 (-7150 3375);
PAINT GREEN (-7150 3375);
DISPLAY INVISIBLE (-7150 3375);
FORCEPROP 1 LAST OFFPAGE TRUE
J 2
(-7525 3350);
DISPLAY 0.872340 (-7525 3350);
PAINT GREEN (-7525 3350);
DISPLAY INVISIBLE (-7525 3350);
FORCEPROP 2 LAST CDS_LIB mstr_standard
J 2
(-7200 3475);
PAINT MONO (-7200 3475);
DISPLAY INVISIBLE (-7200 3475);
FORCEPROP 2 LAST PATH I22
J 0
(-7425 3525);
DISPLAY 1.021277 (-7425 3525);
PAINT ORANGE (-7425 3525);
DISPLAY INVISIBLE (-7425 3525);
FORCEADD OFFPAGE..1
(-7200 3525);
FORCEPROP 2 LAST $XR0 21 
J 0
(-7421 3525);
DISPLAY 0.638298 (-7421 3525);
PAINT MONO (-7421 3525);
FORCEPROP 1 LAST COMMENT_BODY TRUE
J 0
(-7075 3425);
DISPLAY 0.872340 (-7075 3425);
PAINT GREEN (-7075 3425);
DISPLAY INVISIBLE (-7075 3425);
FORCEPROP 1 LAST OFFPAGE TRUE
J 0
(-6875 3400);
DISPLAY 0.872340 (-6875 3400);
PAINT GREEN (-6875 3400);
DISPLAY INVISIBLE (-6875 3400);
FORCEPROP 2 LAST CDS_LIB mstr_standard
J 0
(-7200 3525);
PAINT MONO (-7200 3525);
DISPLAY INVISIBLE (-7200 3525);
FORCEPROP 2 LAST PATH I23
J 0
(-7450 3575);
DISPLAY 1.021277 (-7450 3575);
PAINT ORANGE (-7450 3575);
DISPLAY INVISIBLE (-7450 3575);
FORCEADD RES..1
(-6250 3525);
FORCEPROP 1 LASTPIN (-6150 3525) $PN 2
J 0
(-6188 3537);
DISPLAY 0.617021 (-6188 3537);
PAINT ORANGE (-6188 3537);
FORCEPROP 1 LASTPIN (-6350 3525) $PN 1
J 0
(-6338 3537);
DISPLAY 0.617021 (-6338 3537);
PAINT ORANGE (-6338 3537);
FORCEPROP 1 LAST VALUE 10.0
J 2
(-6225 3625);
DISPLAY 0.617021 (-6225 3625);
PAINT SKYBLUE (-6225 3625);
FORCEPROP 1 LAST TOLERANCE 1%
J 0
(-6200 3625);
DISPLAY 0.617021 (-6200 3625);
PAINT SKYBLUE (-6200 3625);
FORCEPROP 1 LAST WATTAGE 1/16W
J 2
(-6000 3625);
DISPLAY 0.617021 (-6000 3625);
PAINT SKYBLUE (-6000 3625);
FORCEPROP 1 LAST LOCATION R6W26
J 0
(-6475 3625);
DISPLAY 0.617021 (-6475 3625);
PAINT AQUA (-6475 3625);
FORCEPROP 1 LAST PART_NUMBER G21796-066
J 0
(-6475 3575);
DISPLAY 0.617021 (-6475 3575);
PAINT BLUE (-6475 3575);
FORCEPROP 1 LAST MATERIAL CHIP
J 0
(-6250 3575);
DISPLAY 0.617021 (-6250 3575);
PAINT SKYBLUE (-6250 3575);
FORCEPROP 1 LAST PACK_TYPE 0402
J 0
(-6125 3575);
DISPLAY 0.617021 (-6125 3575);
PAINT SKYBLUE (-6125 3575);
FORCEPROP 2 LAST CDS_LOCATION R6W26
J 0
(-6250 3600);
DISPLAY 0.617021 (-6250 3600);
PAINT AQUA (-6250 3600);
DISPLAY INVISIBLE (-6250 3600);
FORCEPROP 2 LAST SEC 1
J 0
(-6300 3725);
DISPLAY 0.680851 (-6300 3725);
PAINT MONO (-6300 3725);
DISPLAY INVISIBLE (-6300 3725);
FORCEPROP 2 LAST CDS_LIB mstr_discrete
J 0
(-6250 3525);
PAINT MONO (-6250 3525);
DISPLAY INVISIBLE (-6250 3525);
FORCEPROP 2 LAST SEC_TYPE 0402
J 0
(-6300 3725);
DISPLAY 1.021277 (-6300 3725);
PAINT ORANGE (-6300 3725);
DISPLAY INVISIBLE (-6300 3725);
FORCEPROP 0 LAST ROOM CPU1
J 0
(-6250 3700);
DISPLAY 1.021277 (-6250 3700);
PAINT ORANGE (-6250 3700);
DISPLAY INVISIBLE (-6250 3700);
FORCEPROP 0 LAST CDS_SEC 1
J 0
(-6250 3650);
PAINT MONO (-6250 3650);
DISPLAY INVISIBLE (-6250 3650);
FORCEPROP 1 LAST PATH I24
J 0
(-6300 3675);
DISPLAY 0.978723 (-6300 3675);
PAINT WHITE (-6300 3675);
DISPLAY INVISIBLE (-6300 3675);
FORCEADD RES..1
(-5900 3475);
FORCEPROP 1 LASTPIN (-6000 3475) $PN 1
J 0
(-5988 3487);
DISPLAY 0.617021 (-5988 3487);
PAINT ORANGE (-5988 3487);
FORCEPROP 1 LASTPIN (-5800 3475) $PN 2
J 0
(-5838 3487);
DISPLAY 0.617021 (-5838 3487);
PAINT ORANGE (-5838 3487);
FORCEPROP 1 LAST PART_NUMBER G21796-066
J 0
(-6125 3375);
DISPLAY 0.617021 (-6125 3375);
PAINT BLUE (-6125 3375);
FORCEPROP 1 LAST WATTAGE 1/16W
J 2
(-5625 3425);
DISPLAY 0.617021 (-5625 3425);
PAINT SKYBLUE (-5625 3425);
FORCEPROP 1 LAST LOCATION R6W27
J 0
(-6125 3425);
DISPLAY 0.617021 (-6125 3425);
PAINT AQUA (-6125 3425);
FORCEPROP 1 LAST TOLERANCE 1%
J 0
(-5825 3425);
DISPLAY 0.617021 (-5825 3425);
PAINT SKYBLUE (-5825 3425);
FORCEPROP 1 LAST VALUE 10.0
J 2
(-5875 3425);
DISPLAY 0.617021 (-5875 3425);
PAINT SKYBLUE (-5875 3425);
FORCEPROP 1 LAST MATERIAL CHIP
J 0
(-5875 3375);
DISPLAY 0.617021 (-5875 3375);
PAINT SKYBLUE (-5875 3375);
FORCEPROP 1 LAST PACK_TYPE 0402
J 0
(-5750 3375);
DISPLAY 0.617021 (-5750 3375);
PAINT SKYBLUE (-5750 3375);
FORCEPROP 2 LAST SEC 1
J 0
(-5950 3675);
DISPLAY 0.680851 (-5950 3675);
PAINT MONO (-5950 3675);
DISPLAY INVISIBLE (-5950 3675);
FORCEPROP 2 LAST CDS_LIB mstr_discrete
J 0
(-5900 3475);
PAINT MONO (-5900 3475);
DISPLAY INVISIBLE (-5900 3475);
FORCEPROP 2 LAST SEC_TYPE 0402
J 0
(-5950 3675);
DISPLAY 1.021277 (-5950 3675);
PAINT ORANGE (-5950 3675);
DISPLAY INVISIBLE (-5950 3675);
FORCEPROP 0 LAST ROOM CPU1
J 0
(-5900 3675);
DISPLAY 1.021277 (-5900 3675);
PAINT ORANGE (-5900 3675);
DISPLAY INVISIBLE (-5900 3675);
FORCEPROP 0 LAST CDS_SEC 1
J 0
(-5900 3625);
PAINT MONO (-5900 3625);
DISPLAY INVISIBLE (-5900 3625);
FORCEPROP 1 LAST PATH I25
J 0
(-5950 3625);
DISPLAY 0.978723 (-5950 3625);
PAINT WHITE (-5950 3625);
DISPLAY INVISIBLE (-5950 3625);
FORCEPROP 2 LAST CDS_LOCATION R6W27
J 0
(-5900 3575);
DISPLAY 0.617021 (-5900 3575);
PAINT AQUA (-5900 3575);
DISPLAY INVISIBLE (-5900 3575);
FORCEADD RES..2
R 2
(-4750 3875);
FORCEPROP 1 LASTPIN (-4750 3975) $PN 1
J 2
(-4755 3937);
DISPLAY 0.617021 (-4755 3937);
PAINT ORANGE (-4755 3937);
FORCEPROP 1 LAST LOCATION R9W19
J 2
(-4795 4000);
DISPLAY 0.617021 (-4795 4000);
PAINT AQUA (-4795 4000);
FORCEPROP 1 LAST VALUE 240
J 2
(-4795 3950);
DISPLAY 0.617021 (-4795 3950);
PAINT SKYBLUE (-4795 3950);
FORCEPROP 1 LAST TOLERANCE 1.0%
J 2
(-4795 3900);
DISPLAY 0.617021 (-4795 3900);
PAINT SKYBLUE (-4795 3900);
FORCEPROP 1 LAST WATTAGE 1/16W
J 2
(-4790 3850);
DISPLAY 0.617021 (-4790 3850);
PAINT SKYBLUE (-4790 3850);
FORCEPROP 1 LAST MATERIAL CHIP
J 2
(-4790 3800);
DISPLAY 0.617021 (-4790 3800);
PAINT SKYBLUE (-4790 3800);
FORCEPROP 1 LAST PART_NUMBER G21796-294
J 2
(-4790 3750);
DISPLAY 0.617021 (-4790 3750);
PAINT BLUE (-4790 3750);
FORCEPROP 1 LASTPIN (-4750 3775) $PN 2
J 2
(-4755 3785);
DISPLAY 0.617021 (-4755 3785);
PAINT ORANGE (-4755 3785);
FORCEPROP 1 LAST PACK_TYPE 0402
J 2
(-4790 3700);
DISPLAY 0.617021 (-4790 3700);
PAINT SKYBLUE (-4790 3700);
FORCEPROP 2 LAST CDS_LOCATION R9W19
J 2
(-4795 4000);
DISPLAY 0.617021 (-4795 4000);
PAINT AQUA (-4795 4000);
DISPLAY INVISIBLE (-4795 4000);
FORCEPROP 1 LAST PATH I26
J 2
(-4800 4050);
DISPLAY 0.978723 (-4800 4050);
PAINT WHITE (-4800 4050);
DISPLAY INVISIBLE (-4800 4050);
FORCEPROP 0 LAST CDS_SEC 1
J 0
(-4775 4050);
PAINT MONO (-4775 4050);
DISPLAY INVISIBLE (-4775 4050);
FORCEPROP 0 LAST ROOM SMB_PE_HP_CPU1
J 0
(-4775 4100);
DISPLAY 1.021277 (-4775 4100);
PAINT ORANGE (-4775 4100);
DISPLAY INVISIBLE (-4775 4100);
FORCEPROP 2 LAST SEC_TYPE 0402
J 0
(-4800 4100);
DISPLAY 1.021277 (-4800 4100);
PAINT ORANGE (-4800 4100);
DISPLAY INVISIBLE (-4800 4100);
FORCEPROP 2 LAST CDS_LIB mstr_discrete
J 2
(-4750 3875);
PAINT MONO (-4750 3875);
DISPLAY INVISIBLE (-4750 3875);
FORCEPROP 2 LAST SEC 1
J 0
(-4800 4100);
DISPLAY 0.680851 (-4800 4100);
PAINT MONO (-4800 4100);
DISPLAY INVISIBLE (-4800 4100);
FORCEADD RES..2
(-4600 3875);
FORCEPROP 1 LASTPIN (-4600 3975) $PN 1
J 0
(-4595 3937);
DISPLAY 0.617021 (-4595 3937);
PAINT ORANGE (-4595 3937);
FORCEPROP 1 LAST LOCATION R9W18
J 0
(-4555 4000);
DISPLAY 0.617021 (-4555 4000);
PAINT AQUA (-4555 4000);
FORCEPROP 1 LAST VALUE 240
J 0
(-4555 3950);
DISPLAY 0.617021 (-4555 3950);
PAINT SKYBLUE (-4555 3950);
FORCEPROP 1 LAST TOLERANCE 1.0%
J 0
(-4555 3900);
DISPLAY 0.617021 (-4555 3900);
PAINT SKYBLUE (-4555 3900);
FORCEPROP 1 LAST PART_NUMBER G21796-294
J 0
(-4560 3750);
DISPLAY 0.617021 (-4560 3750);
PAINT BLUE (-4560 3750);
FORCEPROP 1 LASTPIN (-4600 3775) $PN 2
J 0
(-4595 3785);
DISPLAY 0.617021 (-4595 3785);
PAINT ORANGE (-4595 3785);
FORCEPROP 1 LAST MATERIAL CHIP
J 0
(-4560 3800);
DISPLAY 0.617021 (-4560 3800);
PAINT SKYBLUE (-4560 3800);
FORCEPROP 1 LAST WATTAGE 1/16W
J 0
(-4560 3850);
DISPLAY 0.617021 (-4560 3850);
PAINT SKYBLUE (-4560 3850);
FORCEPROP 1 LAST PACK_TYPE 0402
J 0
(-4560 3700);
DISPLAY 0.617021 (-4560 3700);
PAINT SKYBLUE (-4560 3700);
FORCEPROP 2 LAST SEC 1
J 0
(-4550 4100);
DISPLAY 0.680851 (-4550 4100);
PAINT MONO (-4550 4100);
DISPLAY INVISIBLE (-4550 4100);
FORCEPROP 2 LAST CDS_LIB mstr_discrete
J 0
(-4600 3875);
PAINT MONO (-4600 3875);
DISPLAY INVISIBLE (-4600 3875);
FORCEPROP 2 LAST SEC_TYPE 0402
J 0
(-4550 4100);
DISPLAY 1.021277 (-4550 4100);
PAINT ORANGE (-4550 4100);
DISPLAY INVISIBLE (-4550 4100);
FORCEPROP 0 LAST ROOM SMB_PE_HP_CPU1
J 0
(-4550 4100);
DISPLAY 1.021277 (-4550 4100);
PAINT ORANGE (-4550 4100);
DISPLAY INVISIBLE (-4550 4100);
FORCEPROP 0 LAST CDS_SEC 1
J 0
(-4550 4050);
PAINT MONO (-4550 4050);
DISPLAY INVISIBLE (-4550 4050);
FORCEPROP 1 LAST PATH I27
J 0
(-4550 4050);
DISPLAY 0.978723 (-4550 4050);
PAINT WHITE (-4550 4050);
DISPLAY INVISIBLE (-4550 4050);
FORCEPROP 2 LAST CDS_LOCATION R9W18
J 0
(-4555 4000);
DISPLAY 0.617021 (-4555 4000);
PAINT AQUA (-4555 4000);
DISPLAY INVISIBLE (-4555 4000);
FORCEADD GND..1
(-4200 3825);
FORCEPROP 3 LASTPIN (-4200 3875) SIG_NAME GND\g
J 0
(-4190 3885);
DISPLAY 0.659574 (-4190 3885);
PAINT MONO (-4190 3885);
DISPLAY INVISIBLE (-4190 3885);
FORCEPROP 1 LAST HDL_POWER GND
J 0
(-4200 3975);
DISPLAY 0.872340 (-4200 3975);
PAINT GREEN (-4200 3975);
DISPLAY INVISIBLE (-4200 3975);
FORCEPROP 1 LAST BODY_TYPE PLUMBING
J 0
(-4245 3782);
DISPLAY 0.340426 (-4245 3782);
PAINT GREEN (-4245 3782);
DISPLAY INVISIBLE (-4245 3782);
FORCEPROP 1 LAST VOLTAGE 0
J 0
(-4200 3825);
PAINT SKYBLUE (-4200 3825);
DISPLAY INVISIBLE (-4200 3825);
FORCEPROP 2 LAST CDS_LIB mstr_symbols
J 0
(-4200 3825);
PAINT MONO (-4200 3825);
DISPLAY INVISIBLE (-4200 3825);
FORCEPROP 1 LAST SIZE 1B
J 0
(-4125 3775);
DISPLAY 0.872340 (-4125 3775);
PAINT GREEN (-4125 3775);
DISPLAY INVISIBLE (-4125 3775);
FORCEPROP 2 LAST BOM_COST NT_BASE_VRD
J 0
(-4500 3900);
DISPLAY 0.617021 (-4500 3900);
PAINT ORANGE (-4500 3900);
DISPLAY INVISIBLE (-4500 3900);
FORCEPROP 2 LAST ROOM P2V5_LAN_AUX_VR
J 0
(-4500 3900);
DISPLAY 0.617021 (-4500 3900);
PAINT ORANGE (-4500 3900);
DISPLAY INVISIBLE (-4500 3900);
FORCEPROP 1 LAST PATH I29
J 0
(-4125 3825);
DISPLAY 0.872340 (-4125 3825);
PAINT AQUA (-4125 3825);
DISPLAY INVISIBLE (-4125 3825);
FORCEADD CAP_A..1
(-4200 4050);
FORCEPROP 1 LAST LOCATION C9W8
J 0
(-4150 4150);
DISPLAY 0.617021 (-4150 4150);
PAINT AQUA (-4150 4150);
FORCEPROP 1 LASTPIN (-4200 4150) $PN 1
J 0
(-4190 4130);
DISPLAY 0.617021 (-4190 4130);
PAINT ORANGE (-4190 4130);
FORCEPROP 1 LAST PACK_TYPE 0402V
J 0
(-4150 3850);
DISPLAY 0.617021 (-4150 3850);
PAINT SKYBLUE (-4150 3850);
FORCEPROP 1 LAST TOLERANCE 10%
J 0
(-4150 4000);
DISPLAY 0.617021 (-4150 4000);
PAINT SKYBLUE (-4150 4000);
FORCEPROP 1 LAST MATERIAL X7R
J 0
(-4150 3950);
DISPLAY 0.617021 (-4150 3950);
PAINT SKYBLUE (-4150 3950);
FORCEPROP 1 LASTPIN (-4200 3950) $PN 2
J 0
(-4190 3930);
DISPLAY 0.617021 (-4190 3930);
PAINT ORANGE (-4190 3930);
FORCEPROP 1 LAST PART_NUMBER A36096-030
J 0
(-4150 3900);
DISPLAY 0.617021 (-4150 3900);
PAINT BLUE (-4150 3900);
FORCEPROP 1 LAST VOLTAGE 16V
J 0
(-4150 4050);
DISPLAY 0.617021 (-4150 4050);
PAINT SKYBLUE (-4150 4050);
FORCEPROP 1 LAST VALUE 0.1UF
J 0
(-4150 4100);
DISPLAY 0.617021 (-4150 4100);
PAINT SKYBLUE (-4150 4100);
FORCEPROP 2 LAST CDS_LIB dev_discrete
J 0
(-4200 4050);
PAINT ORANGE (-4200 4050);
DISPLAY INVISIBLE (-4200 4050);
FORCEPROP 2 LAST SEC 1
J 0
(-4150 4250);
DISPLAY 0.680851 (-4150 4250);
PAINT MONO (-4150 4250);
DISPLAY INVISIBLE (-4150 4250);
FORCEPROP 2 LAST SEC_TYPE 0402V
J 0
(-4150 4250);
DISPLAY 1.021277 (-4150 4250);
PAINT ORANGE (-4150 4250);
DISPLAY INVISIBLE (-4150 4250);
FORCEPROP 0 LAST ROOM SMB_PE_HP_CPU1
J 0
(-4150 4250);
DISPLAY 1.021277 (-4150 4250);
PAINT ORANGE (-4150 4250);
DISPLAY INVISIBLE (-4150 4250);
FORCEPROP 0 LAST CDS_SEC 1
J 0
(-4150 4200);
PAINT MONO (-4150 4200);
DISPLAY INVISIBLE (-4150 4200);
FORCEPROP 1 LAST PATH I30
J 0
(-4150 4200);
DISPLAY 0.978723 (-4150 4200);
PAINT WHITE (-4150 4200);
DISPLAY INVISIBLE (-4150 4200);
FORCEPROP 2 LAST CDS_LOCATION C9W8
J 0
(-4150 4150);
DISPLAY 0.617021 (-4150 4150);
PAINT AQUA (-4150 4150);
DISPLAY INVISIBLE (-4150 4150);
FORCEADD GND..1
(-3525 3825);
FORCEPROP 3 LASTPIN (-3525 3875) SIG_NAME GND\g
J 0
(-3515 3885);
DISPLAY 0.659574 (-3515 3885);
PAINT MONO (-3515 3885);
DISPLAY INVISIBLE (-3515 3885);
FORCEPROP 2 LAST ROOM P2V5_LAN_AUX_VR
J 0
(-3825 3900);
DISPLAY 0.617021 (-3825 3900);
PAINT ORANGE (-3825 3900);
DISPLAY INVISIBLE (-3825 3900);
FORCEPROP 2 LAST BOM_COST NT_BASE_VRD
J 0
(-3825 3900);
DISPLAY 0.617021 (-3825 3900);
PAINT ORANGE (-3825 3900);
DISPLAY INVISIBLE (-3825 3900);
FORCEPROP 1 LAST SIZE 1B
J 0
(-3450 3775);
DISPLAY 0.872340 (-3450 3775);
PAINT GREEN (-3450 3775);
DISPLAY INVISIBLE (-3450 3775);
FORCEPROP 1 LAST VOLTAGE 0
J 0
(-3525 3825);
PAINT SKYBLUE (-3525 3825);
DISPLAY INVISIBLE (-3525 3825);
FORCEPROP 1 LAST BODY_TYPE PLUMBING
J 0
(-3570 3782);
DISPLAY 0.340426 (-3570 3782);
PAINT GREEN (-3570 3782);
DISPLAY INVISIBLE (-3570 3782);
FORCEPROP 1 LAST HDL_POWER GND
J 0
(-3525 3975);
DISPLAY 0.872340 (-3525 3975);
PAINT GREEN (-3525 3975);
DISPLAY INVISIBLE (-3525 3975);
FORCEPROP 1 LAST PATH I31
J 0
(-3450 3825);
DISPLAY 0.872340 (-3450 3825);
PAINT AQUA (-3450 3825);
DISPLAY INVISIBLE (-3450 3825);
FORCEPROP 2 LAST CDS_LIB mstr_symbols
J 0
(-3525 3825);
PAINT MONO (-3525 3825);
DISPLAY INVISIBLE (-3525 3825);
FORCEADD CAP_A..1
R 2
(-3525 4050);
FORCEPROP 1 LASTPIN (-3525 3950) $PN 2
J 2
(-3535 3930);
DISPLAY 0.617021 (-3535 3930);
PAINT ORANGE (-3535 3930);
FORCEPROP 1 LAST LOCATION C9W7
J 2
(-3575 4150);
DISPLAY 0.617021 (-3575 4150);
PAINT AQUA (-3575 4150);
FORCEPROP 1 LAST VALUE 0.1UF
J 2
(-3575 4100);
DISPLAY 0.617021 (-3575 4100);
PAINT SKYBLUE (-3575 4100);
FORCEPROP 1 LAST VOLTAGE 16V
J 2
(-3575 4050);
DISPLAY 0.617021 (-3575 4050);
PAINT SKYBLUE (-3575 4050);
FORCEPROP 1 LAST TOLERANCE 10%
J 2
(-3575 4000);
DISPLAY 0.617021 (-3575 4000);
PAINT SKYBLUE (-3575 4000);
FORCEPROP 1 LASTPIN (-3525 4150) $PN 1
J 2
(-3535 4130);
DISPLAY 0.617021 (-3535 4130);
PAINT ORANGE (-3535 4130);
FORCEPROP 1 LAST MATERIAL X7R
J 2
(-3575 3950);
DISPLAY 0.617021 (-3575 3950);
PAINT SKYBLUE (-3575 3950);
FORCEPROP 1 LAST PACK_TYPE 0402V
J 2
(-3575 3850);
DISPLAY 0.617021 (-3575 3850);
PAINT SKYBLUE (-3575 3850);
FORCEPROP 1 LAST PART_NUMBER A36096-030
J 2
(-3575 3900);
DISPLAY 0.617021 (-3575 3900);
PAINT BLUE (-3575 3900);
FORCEPROP 2 LAST SEC_TYPE 0402V
J 0
(-3575 4250);
DISPLAY 1.021277 (-3575 4250);
PAINT ORANGE (-3575 4250);
DISPLAY INVISIBLE (-3575 4250);
FORCEPROP 2 LAST SEC 1
J 0
(-3575 4250);
DISPLAY 0.680851 (-3575 4250);
PAINT MONO (-3575 4250);
DISPLAY INVISIBLE (-3575 4250);
FORCEPROP 2 LAST CDS_LIB dev_discrete
J 0
(-3525 4050);
PAINT ORANGE (-3525 4050);
DISPLAY INVISIBLE (-3525 4050);
FORCEPROP 0 LAST ROOM SMB_PE_HP_CPU1
J 0
(-3575 4250);
DISPLAY 1.021277 (-3575 4250);
PAINT ORANGE (-3575 4250);
DISPLAY INVISIBLE (-3575 4250);
FORCEPROP 0 LAST CDS_SEC 1
J 0
(-3575 4200);
PAINT MONO (-3575 4200);
DISPLAY INVISIBLE (-3575 4200);
FORCEPROP 1 LAST PATH I32
J 2
(-3575 4200);
DISPLAY 0.978723 (-3575 4200);
PAINT WHITE (-3575 4200);
DISPLAY INVISIBLE (-3575 4200);
FORCEPROP 2 LAST CDS_LOCATION C9W7
J 2
(-3575 4150);
DISPLAY 0.617021 (-3575 4150);
PAINT AQUA (-3575 4150);
DISPLAY INVISIBLE (-3575 4150);
FORCEADD RES..2
(-2850 3875);
FORCEPROP 1 LAST VALUE 2.0K
J 0
(-2805 3950);
DISPLAY 0.617021 (-2805 3950);
PAINT SKYBLUE (-2805 3950);
FORCEPROP 1 LAST LOCATION R9W16
J 0
(-2805 4000);
DISPLAY 0.617021 (-2805 4000);
PAINT AQUA (-2805 4000);
FORCEPROP 1 LAST WATTAGE 1/16W
J 0
(-2810 3850);
DISPLAY 0.617021 (-2810 3850);
PAINT SKYBLUE (-2810 3850);
FORCEPROP 1 LAST TOLERANCE 1%
J 0
(-2805 3900);
DISPLAY 0.617021 (-2805 3900);
PAINT SKYBLUE (-2805 3900);
FORCEPROP 1 LAST MATERIAL CHIP
J 0
(-2810 3800);
DISPLAY 0.617021 (-2810 3800);
PAINT SKYBLUE (-2810 3800);
FORCEPROP 1 LASTPIN (-2850 3975) $PN 1
J 0
(-2845 3937);
DISPLAY 0.617021 (-2845 3937);
PAINT ORANGE (-2845 3937);
FORCEPROP 1 LASTPIN (-2850 3775) $PN 2
J 0
(-2845 3785);
DISPLAY 0.617021 (-2845 3785);
PAINT ORANGE (-2845 3785);
FORCEPROP 1 LAST PACK_TYPE 0402
J 0
(-2810 3700);
DISPLAY 0.617021 (-2810 3700);
PAINT SKYBLUE (-2810 3700);
FORCEPROP 1 LAST PART_NUMBER G21796-001
J 0
(-2810 3750);
DISPLAY 0.617021 (-2810 3750);
PAINT BLUE (-2810 3750);
FORCEPROP 2 LAST SEC 1
J 0
(-2800 4100);
DISPLAY 0.680851 (-2800 4100);
PAINT MONO (-2800 4100);
DISPLAY INVISIBLE (-2800 4100);
FORCEPROP 2 LAST CDS_LIB mstr_discrete
J 0
(-2850 3875);
PAINT MONO (-2850 3875);
DISPLAY INVISIBLE (-2850 3875);
FORCEPROP 2 LAST SEC_TYPE 0402
J 0
(-2800 4100);
DISPLAY 1.021277 (-2800 4100);
PAINT ORANGE (-2800 4100);
DISPLAY INVISIBLE (-2800 4100);
FORCEPROP 0 LAST ROOM SMB_PE_HP_CPU1
J 0
(-2800 4100);
DISPLAY 1.021277 (-2800 4100);
PAINT ORANGE (-2800 4100);
DISPLAY INVISIBLE (-2800 4100);
FORCEPROP 0 LAST CDS_SEC 1
J 0
(-2800 4050);
PAINT MONO (-2800 4050);
DISPLAY INVISIBLE (-2800 4050);
FORCEPROP 1 LAST PATH I34
J 0
(-2800 4050);
DISPLAY 0.978723 (-2800 4050);
PAINT WHITE (-2800 4050);
DISPLAY INVISIBLE (-2800 4050);
FORCEPROP 2 LAST CDS_LOCATION R9W16
J 0
(-2805 4000);
DISPLAY 0.617021 (-2805 4000);
PAINT AQUA (-2805 4000);
DISPLAY INVISIBLE (-2805 4000);
FORCEADD RES..2
R 2
(-3000 3875);
FORCEPROP 1 LAST VALUE 2.0K
J 2
(-3045 3950);
DISPLAY 0.617021 (-3045 3950);
PAINT SKYBLUE (-3045 3950);
FORCEPROP 1 LASTPIN (-3000 3775) $PN 2
J 2
(-3005 3785);
DISPLAY 0.617021 (-3005 3785);
PAINT ORANGE (-3005 3785);
FORCEPROP 1 LASTPIN (-3000 3975) $PN 1
J 2
(-3005 3937);
DISPLAY 0.617021 (-3005 3937);
PAINT ORANGE (-3005 3937);
FORCEPROP 1 LAST TOLERANCE 1%
J 2
(-3045 3900);
DISPLAY 0.617021 (-3045 3900);
PAINT SKYBLUE (-3045 3900);
FORCEPROP 1 LAST PACK_TYPE 0402
J 2
(-3040 3700);
DISPLAY 0.617021 (-3040 3700);
PAINT SKYBLUE (-3040 3700);
FORCEPROP 1 LAST MATERIAL CHIP
J 2
(-3040 3800);
DISPLAY 0.617021 (-3040 3800);
PAINT SKYBLUE (-3040 3800);
FORCEPROP 1 LAST WATTAGE 1/16W
J 2
(-3040 3850);
DISPLAY 0.617021 (-3040 3850);
PAINT SKYBLUE (-3040 3850);
FORCEPROP 1 LAST LOCATION R9W17
J 2
(-3045 4000);
DISPLAY 0.617021 (-3045 4000);
PAINT AQUA (-3045 4000);
FORCEPROP 1 LAST PART_NUMBER G21796-001
J 2
(-3040 3750);
DISPLAY 0.617021 (-3040 3750);
PAINT BLUE (-3040 3750);
FORCEPROP 2 LAST SEC 1
J 0
(-3050 4100);
DISPLAY 0.680851 (-3050 4100);
PAINT MONO (-3050 4100);
DISPLAY INVISIBLE (-3050 4100);
FORCEPROP 2 LAST SEC_TYPE 0402
J 0
(-3050 4100);
DISPLAY 1.021277 (-3050 4100);
PAINT ORANGE (-3050 4100);
DISPLAY INVISIBLE (-3050 4100);
FORCEPROP 2 LAST CDS_LIB mstr_discrete
J 2
(-3000 3875);
PAINT MONO (-3000 3875);
DISPLAY INVISIBLE (-3000 3875);
FORCEPROP 0 LAST ROOM SMB_PE_HP_CPU1
J 0
(-3025 4100);
DISPLAY 1.021277 (-3025 4100);
PAINT ORANGE (-3025 4100);
DISPLAY INVISIBLE (-3025 4100);
FORCEPROP 0 LAST CDS_SEC 1
J 0
(-3025 4050);
PAINT MONO (-3025 4050);
DISPLAY INVISIBLE (-3025 4050);
FORCEPROP 1 LAST PATH I35
J 2
(-3050 4050);
DISPLAY 0.978723 (-3050 4050);
PAINT WHITE (-3050 4050);
DISPLAY INVISIBLE (-3050 4050);
FORCEPROP 2 LAST CDS_LOCATION R9W17
J 2
(-3045 4000);
DISPLAY 0.617021 (-3045 4000);
PAINT AQUA (-3045 4000);
DISPLAY INVISIBLE (-3045 4000);
FORCEADD P3V3_STBY..1
(-2925 4275);
FORCEPROP 3 LASTPIN (-2925 4225) SIG_NAME P3V3_STBY\g
J 0
(-2915 4235);
DISPLAY 0.659574 (-2915 4235);
PAINT MONO (-2915 4235);
DISPLAY INVISIBLE (-2915 4235);
FORCEPROP 2 LAST CDS_LIB mstr_symbols
J 0
(-2925 4275);
PAINT ORANGE (-2925 4275);
DISPLAY INVISIBLE (-2925 4275);
FORCEPROP 1 LAST PATH I36
J 0
(-2880 4277);
DISPLAY 0.340426 (-2880 4277);
PAINT GREEN (-2880 4277);
DISPLAY INVISIBLE (-2880 4277);
FORCEPROP 1 LAST SIZE 1B
J 0
(-2880 4297);
DISPLAY 0.340426 (-2880 4297);
PAINT GREEN (-2880 4297);
DISPLAY INVISIBLE (-2880 4297);
FORCEPROP 1 LAST VOLTAGE 3.3V
J 0
(-2970 4232);
DISPLAY 0.340426 (-2970 4232);
PAINT SKYBLUE (-2970 4232);
DISPLAY INVISIBLE (-2970 4232);
FORCEPROP 1 LAST BODY_TYPE PLUMBING
J 0
(-2970 4232);
DISPLAY 0.340426 (-2970 4232);
PAINT GREEN (-2970 4232);
DISPLAY INVISIBLE (-2970 4232);
FORCEPROP 1 LAST HDL_POWER P3V3_STBY
J 0
(-3225 4150);
DISPLAY 0.872340 (-3225 4150);
PAINT ORANGE (-3225 4150);
DISPLAY INVISIBLE (-3225 4150);
FORCEADD RES..1
(-2450 3525);
FORCEPROP 1 LAST LOCATION R9W14
J 0
(-2500 3575);
DISPLAY 0.617021 (-2500 3575);
PAINT AQUA (-2500 3575);
FORCEPROP 1 LAST MATERIAL CHIP
J 0
(-2450 3375);
DISPLAY 0.617021 (-2450 3375);
PAINT SKYBLUE (-2450 3375);
FORCEPROP 1 LASTPIN (-2350 3525) $PN 2
J 0
(-2388 3537);
DISPLAY 0.787234 (-2388 3537);
PAINT ORANGE (-2388 3537);
FORCEPROP 1 LASTPIN (-2550 3525) $PN 1
J 0
(-2538 3537);
DISPLAY 0.787234 (-2538 3537);
PAINT ORANGE (-2538 3537);
FORCEPROP 1 LAST PACK_TYPE 0402
J 0
(-2475 3325);
DISPLAY 0.617021 (-2475 3325);
PAINT SKYBLUE (-2475 3325);
FORCEPROP 1 LAST TOLERANCE 1%
J 0
(-2450 3425);
DISPLAY 0.617021 (-2450 3425);
PAINT SKYBLUE (-2450 3425);
FORCEPROP 1 LAST WATTAGE 1/16W
J 2
(-2475 3375);
DISPLAY 0.617021 (-2475 3375);
PAINT SKYBLUE (-2475 3375);
FORCEPROP 1 LAST VALUE 20.0
J 2
(-2475 3425);
DISPLAY 0.617021 (-2475 3425);
PAINT SKYBLUE (-2475 3425);
FORCEPROP 1 LAST PART_NUMBER G21796-173
J 0
(-2500 3625);
DISPLAY 0.617021 (-2500 3625);
PAINT BLUE (-2500 3625);
FORCEPROP 2 LAST CDS_LIB mstr_discrete
J 0
(-2450 3525);
PAINT ORANGE (-2450 3525);
DISPLAY INVISIBLE (-2450 3525);
FORCEPROP 0 LAST ROOM SMB_PE_HP_CPU1
J 0
(-2500 3725);
DISPLAY 1.021277 (-2500 3725);
PAINT ORANGE (-2500 3725);
DISPLAY INVISIBLE (-2500 3725);
FORCEPROP 1 LAST PATH I37
J 0
(-2500 3675);
DISPLAY 0.978723 (-2500 3675);
PAINT WHITE (-2500 3675);
DISPLAY INVISIBLE (-2500 3675);
FORCEPROP 2 LAST CDS_LOCATION R9W14
J 0
(-2500 3575);
DISPLAY 0.617021 (-2500 3575);
PAINT AQUA (-2500 3575);
DISPLAY INVISIBLE (-2500 3575);
FORCEPROP 2 LAST SEC 1
J 0
(-2500 3725);
PAINT MONO (-2500 3725);
DISPLAY INVISIBLE (-2500 3725);
FORCEPROP 2 LAST SEC_TYPE 0402
J 0
(-2500 3725);
DISPLAY 1.021277 (-2500 3725);
PAINT ORANGE (-2500 3725);
DISPLAY INVISIBLE (-2500 3725);
FORCEADD RES..1
(-2200 3475);
FORCEPROP 1 LASTPIN (-2100 3475) $PN 2
J 0
(-2138 3487);
DISPLAY 0.787234 (-2138 3487);
PAINT ORANGE (-2138 3487);
FORCEPROP 1 LASTPIN (-2300 3475) $PN 1
J 0
(-2288 3487);
DISPLAY 0.787234 (-2288 3487);
PAINT ORANGE (-2288 3487);
FORCEPROP 1 LAST PACK_TYPE 0402
J 0
(-2200 3275);
DISPLAY 0.617021 (-2200 3275);
PAINT SKYBLUE (-2200 3275);
FORCEPROP 1 LAST VALUE 20.0
J 2
(-2225 3375);
DISPLAY 0.617021 (-2225 3375);
PAINT SKYBLUE (-2225 3375);
FORCEPROP 1 LAST TOLERANCE 1%
J 0
(-2200 3375);
DISPLAY 0.617021 (-2200 3375);
PAINT SKYBLUE (-2200 3375);
FORCEPROP 1 LAST MATERIAL CHIP
J 0
(-2200 3325);
DISPLAY 0.617021 (-2200 3325);
PAINT SKYBLUE (-2200 3325);
FORCEPROP 1 LAST WATTAGE 1/16W
J 2
(-2225 3325);
DISPLAY 0.617021 (-2225 3325);
PAINT SKYBLUE (-2225 3325);
FORCEPROP 1 LAST PART_NUMBER G21796-173
J 0
(-2250 3575);
DISPLAY 0.617021 (-2250 3575);
PAINT BLUE (-2250 3575);
FORCEPROP 1 LAST LOCATION R9W13
J 0
(-2250 3525);
DISPLAY 0.617021 (-2250 3525);
PAINT AQUA (-2250 3525);
FORCEPROP 2 LAST CDS_LOCATION R9W13
J 0
(-2250 3525);
DISPLAY 0.617021 (-2250 3525);
PAINT AQUA (-2250 3525);
DISPLAY INVISIBLE (-2250 3525);
FORCEPROP 2 LAST CDS_LIB mstr_discrete
J 0
(-2200 3475);
PAINT ORANGE (-2200 3475);
DISPLAY INVISIBLE (-2200 3475);
FORCEPROP 2 LAST SEC_TYPE 0402
J 0
(-2250 3675);
DISPLAY 1.021277 (-2250 3675);
PAINT ORANGE (-2250 3675);
DISPLAY INVISIBLE (-2250 3675);
FORCEPROP 2 LAST SEC 1
J 0
(-2250 3675);
PAINT MONO (-2250 3675);
DISPLAY INVISIBLE (-2250 3675);
FORCEPROP 1 LAST PATH I38
J 0
(-2250 3625);
DISPLAY 0.978723 (-2250 3625);
PAINT WHITE (-2250 3625);
DISPLAY INVISIBLE (-2250 3625);
FORCEPROP 0 LAST ROOM SMB_PE_HP_CPU1
J 0
(-2250 3675);
DISPLAY 1.021277 (-2250 3675);
PAINT ORANGE (-2250 3675);
DISPLAY INVISIBLE (-2250 3675);
FORCEADD P3V3_STBY..1
(-3450 4375);
FORCEPROP 3 LASTPIN (-3450 4325) SIG_NAME P3V3_STBY\g
J 0
(-3440 4335);
DISPLAY 0.659574 (-3440 4335);
PAINT MONO (-3440 4335);
DISPLAY INVISIBLE (-3440 4335);
FORCEPROP 1 LAST HDL_POWER P3V3_STBY
J 0
(-3750 4250);
DISPLAY 0.872340 (-3750 4250);
PAINT ORANGE (-3750 4250);
DISPLAY INVISIBLE (-3750 4250);
FORCEPROP 1 LAST BODY_TYPE PLUMBING
J 0
(-3495 4332);
DISPLAY 0.340426 (-3495 4332);
PAINT GREEN (-3495 4332);
DISPLAY INVISIBLE (-3495 4332);
FORCEPROP 1 LAST VOLTAGE 3.3V
J 0
(-3495 4332);
DISPLAY 0.340426 (-3495 4332);
PAINT SKYBLUE (-3495 4332);
DISPLAY INVISIBLE (-3495 4332);
FORCEPROP 2 LAST CDS_LIB mstr_symbols
J 0
(-3450 4375);
PAINT ORANGE (-3450 4375);
DISPLAY INVISIBLE (-3450 4375);
FORCEPROP 1 LAST SIZE 1B
J 0
(-3405 4397);
DISPLAY 0.340426 (-3405 4397);
PAINT GREEN (-3405 4397);
DISPLAY INVISIBLE (-3405 4397);
FORCEPROP 1 LAST PATH I40
J 0
(-3405 4377);
DISPLAY 0.340426 (-3405 4377);
PAINT GREEN (-3405 4377);
DISPLAY INVISIBLE (-3405 4377);
FORCEADD OFFPAGE..3
(-1300 3475);
FORCEPROP 2 LAST $XR0 145 
J 0
(-1086 3475);
DISPLAY 0.638298 (-1086 3475);
PAINT MONO (-1086 3475);
FORCEPROP 2 LAST CDS_LIB mstr_standard
J 2
(-1300 3475);
PAINT MONO (-1300 3475);
DISPLAY INVISIBLE (-1300 3475);
FORCEPROP 2 LAST PATH I44
J 0
(-950 3525);
DISPLAY 1.021277 (-950 3525);
PAINT ORANGE (-950 3525);
DISPLAY INVISIBLE (-950 3525);
FORCEPROP 1 LAST OFFPAGE TRUE
J 0
(-975 3350);
DISPLAY 0.872340 (-975 3350);
PAINT GREEN (-975 3350);
DISPLAY INVISIBLE (-975 3350);
FORCEPROP 1 LAST COMMENT_BODY TRUE
J 0
(-1350 3375);
DISPLAY 0.872340 (-1350 3375);
PAINT GREEN (-1350 3375);
DISPLAY INVISIBLE (-1350 3375);
FORCEADD OFFPAGE..2
(-1275 3525);
FORCEPROP 2 LAST $XR0 145 
J 0
(-1086 3525);
DISPLAY 0.638298 (-1086 3525);
PAINT MONO (-1086 3525);
FORCEPROP 2 LAST CDS_LIB mstr_standard
J 2
(-1275 3525);
PAINT MONO (-1275 3525);
DISPLAY INVISIBLE (-1275 3525);
FORCEPROP 2 LAST PATH I45
J 0
(-950 3575);
DISPLAY 1.021277 (-950 3575);
PAINT ORANGE (-950 3575);
DISPLAY INVISIBLE (-950 3575);
FORCEPROP 1 LAST COMMENT_BODY TRUE
J 0
(-1320 3430);
DISPLAY 0.872340 (-1320 3430);
PAINT GREEN (-1320 3430);
DISPLAY INVISIBLE (-1320 3430);
FORCEPROP 1 LAST OFFPAGE TRUE
J 0
(-950 3400);
DISPLAY 0.872340 (-950 3400);
PAINT GREEN (-950 3400);
DISPLAY INVISIBLE (-950 3400);
FORCEADD PVCCIO_CPU0..1
(-4275 4375);
FORCEPROP 3 LASTPIN (-4275 4325) SIG_NAME PVCCIO_CPU0\g
J 0
(-4265 4335);
DISPLAY 0.659574 (-4265 4335);
PAINT MONO (-4265 4335);
DISPLAY INVISIBLE (-4265 4335);
FORCEPROP 2 LAST CDS_LIB mstr_symbols
J 0
(-4275 4375);
PAINT MONO (-4275 4375);
DISPLAY INVISIBLE (-4275 4375);
FORCEPROP 1 LAST PATH I47
J 0
(-4225 4400);
DISPLAY 0.872340 (-4225 4400);
PAINT AQUA (-4225 4400);
DISPLAY INVISIBLE (-4225 4400);
FORCEPROP 1 LAST VOLTAGE 1.1V
J 0
(-4320 4332);
DISPLAY 0.340426 (-4320 4332);
PAINT SKYBLUE (-4320 4332);
DISPLAY INVISIBLE (-4320 4332);
FORCEPROP 1 LAST BODY_TYPE PLUMBING
J 0
(-4320 4332);
DISPLAY 0.340426 (-4320 4332);
PAINT GREEN (-4320 4332);
DISPLAY INVISIBLE (-4320 4332);
FORCEPROP 1 LAST HDL_POWER PVCCIO_CPU0
J 1
(-4275 4425);
DISPLAY 0.872340 (-4275 4425);
PAINT GREEN (-4275 4425);
DISPLAY INVISIBLE (-4275 4425);
FORCEADD PVCCIO_CPU0..1
(-4700 4250);
FORCEPROP 3 LASTPIN (-4700 4200) SIG_NAME PVCCIO_CPU0\g
J 0
(-4690 4210);
DISPLAY 0.659574 (-4690 4210);
PAINT MONO (-4690 4210);
DISPLAY INVISIBLE (-4690 4210);
FORCEPROP 2 LAST CDS_LIB mstr_symbols
J 0
(-4700 4250);
PAINT MONO (-4700 4250);
DISPLAY INVISIBLE (-4700 4250);
FORCEPROP 1 LAST PATH I48
J 0
(-4650 4275);
DISPLAY 0.872340 (-4650 4275);
PAINT AQUA (-4650 4275);
DISPLAY INVISIBLE (-4650 4275);
FORCEPROP 1 LAST VOLTAGE 1.1V
J 0
(-4745 4207);
DISPLAY 0.340426 (-4745 4207);
PAINT SKYBLUE (-4745 4207);
DISPLAY INVISIBLE (-4745 4207);
FORCEPROP 1 LAST BODY_TYPE PLUMBING
J 0
(-4745 4207);
DISPLAY 0.340426 (-4745 4207);
PAINT GREEN (-4745 4207);
DISPLAY INVISIBLE (-4745 4207);
FORCEPROP 1 LAST HDL_POWER PVCCIO_CPU0
J 1
(-4700 4300);
DISPLAY 0.872340 (-4700 4300);
PAINT GREEN (-4700 4300);
DISPLAY INVISIBLE (-4700 4300);
FORCEADD TCA9517DGKR-GP..1
(-3925 3500);
FORCEPROP 2 LASTPIN (-4250 3425) $PN 4
J 2
(-4260 3435);
DISPLAY 0.808511 (-4260 3435);
PAINT ORANGE (-4260 3435);
FORCEPROP 2 LASTPIN (-4250 3475) $PN 3
J 2
(-4260 3485);
DISPLAY 0.808511 (-4260 3485);
PAINT ORANGE (-4260 3485);
FORCEPROP 2 LASTPIN (-4250 3525) $PN 2
J 2
(-4260 3535);
DISPLAY 0.808511 (-4260 3535);
PAINT ORANGE (-4260 3535);
FORCEPROP 2 LASTPIN (-4250 3575) $PN 1
J 2
(-4260 3585);
DISPLAY 0.808511 (-4260 3585);
PAINT ORANGE (-4260 3585);
FORCEPROP 1 LAST VALUE TCA9517DGKR-GP
J 0
(-4095 3290);
DISPLAY 0.617021 (-4095 3290);
PAINT GREEN (-4095 3290);
FORCEPROP 2 LASTPIN (-3600 3425) $PN 5
J 0
(-3590 3435);
DISPLAY 0.808511 (-3590 3435);
PAINT ORANGE (-3590 3435);
FORCEPROP 2 LASTPIN (-3600 3475) $PN 6
J 0
(-3590 3485);
DISPLAY 0.808511 (-3590 3485);
PAINT ORANGE (-3590 3485);
FORCEPROP 2 LASTPIN (-3600 3525) $PN 7
J 0
(-3590 3535);
DISPLAY 0.808511 (-3590 3535);
PAINT ORANGE (-3590 3535);
FORCEPROP 1 LAST LOCATION U1W2
J 0
(-4095 3685);
DISPLAY 0.617021 (-4095 3685);
PAINT GREEN (-4095 3685);
FORCEPROP 2 LASTPIN (-3600 3575) $PN 8
J 0
(-3590 3585);
DISPLAY 0.808511 (-3590 3585);
PAINT ORANGE (-3590 3585);
FORCEPROP 1 LAST PATH I49
J 0
(-3925 3500);
DISPLAY 0.617021 (-3925 3500);
PAINT GREEN (-3925 3500);
DISPLAY INVISIBLE (-3925 3500);
FORCEPROP 1 LAST CDS_LMAN_SYM_OUTLINE -175,175,175,-175
J 0
(-3925 3500);
DISPLAY 0.468085 (-3925 3500);
PAINT GREEN (-3925 3500);
DISPLAY INVISIBLE (-3925 3500);
FORCEPROP 2 LAST CDS_LIB w_hdl
J 0
(-3925 3500);
PAINT MONO (-3925 3500);
DISPLAY INVISIBLE (-3925 3500);
FORCEPROP 1 LAST PART_NUMBER 071.09517.0009
J 0
(-3925 3500);
DISPLAY 0.617021 (-3925 3500);
PAINT GREEN (-3925 3500);
DISPLAY INVISIBLE (-3925 3500);
FORCEPROP 2 LAST SEC_TYPE DISCRET-G8
J 0
(-4075 3725);
DISPLAY 1.021277 (-4075 3725);
PAINT ORANGE (-4075 3725);
DISPLAY INVISIBLE (-4075 3725);
FORCEPROP 2 LAST SEC 1
J 0
(-4075 3725);
DISPLAY 0.680851 (-4075 3725);
PAINT MONO (-4075 3725);
DISPLAY INVISIBLE (-4075 3725);
FORCEPROP 1 LAST PACK_TYPE DISCRET-G8
J 0
(-3925 3500);
DISPLAY 0.617021 (-3925 3500);
PAINT GREEN (-3925 3500);
DISPLAY INVISIBLE (-3925 3500);
FORCEADD GND..1
(-4300 3325);
FORCEPROP 3 LASTPIN (-4300 3375) SIG_NAME GND\g
J 0
(-4290 3385);
DISPLAY 0.659574 (-4290 3385);
PAINT MONO (-4290 3385);
DISPLAY INVISIBLE (-4290 3385);
FORCEPROP 2 LAST CDS_LIB mstr_symbols
J 0
(-4300 3325);
PAINT MONO (-4300 3325);
DISPLAY INVISIBLE (-4300 3325);
FORCEPROP 1 LAST PATH I50
J 0
(-4225 3325);
DISPLAY 0.872340 (-4225 3325);
PAINT AQUA (-4225 3325);
DISPLAY INVISIBLE (-4225 3325);
FORCEPROP 1 LAST HDL_POWER GND
J 0
(-4300 3475);
DISPLAY 0.872340 (-4300 3475);
PAINT GREEN (-4300 3475);
DISPLAY INVISIBLE (-4300 3475);
FORCEPROP 1 LAST BODY_TYPE PLUMBING
J 0
(-4345 3282);
DISPLAY 0.340426 (-4345 3282);
PAINT GREEN (-4345 3282);
DISPLAY INVISIBLE (-4345 3282);
FORCEPROP 1 LAST VOLTAGE 0
J 0
(-4300 3325);
PAINT SKYBLUE (-4300 3325);
DISPLAY INVISIBLE (-4300 3325);
FORCEPROP 1 LAST SIZE 1B
J 0
(-4225 3275);
DISPLAY 0.872340 (-4225 3275);
PAINT GREEN (-4225 3275);
DISPLAY INVISIBLE (-4225 3275);
FORCEPROP 2 LAST BOM_COST NT_BASE_VRD
J 0
(-4600 3400);
DISPLAY 0.617021 (-4600 3400);
PAINT ORANGE (-4600 3400);
DISPLAY INVISIBLE (-4600 3400);
FORCEPROP 2 LAST ROOM P2V5_LAN_AUX_VR
J 0
(-4600 3400);
DISPLAY 0.617021 (-4600 3400);
PAINT ORANGE (-4600 3400);
DISPLAY INVISIBLE (-4600 3400);
FORCEADD OFFPAGE..3
(-2500 3050);
FORCEPROP 2 LAST $XR0 145 
J 0
(-2286 3050);
DISPLAY 0.638298 (-2286 3050);
PAINT MONO (-2286 3050);
FORCEPROP 2 LAST CDS_LIB mstr_standard
J 0
(-2500 3050);
PAINT MONO (-2500 3050);
DISPLAY INVISIBLE (-2500 3050);
FORCEPROP 2 LAST PATH I51
J 0
(-2300 3125);
DISPLAY 1.021277 (-2300 3125);
PAINT ORANGE (-2300 3125);
DISPLAY INVISIBLE (-2300 3125);
FORCEPROP 1 LAST COMMENT_BODY TRUE
J 0
(-2550 2950);
DISPLAY 0.872340 (-2550 2950);
PAINT GREEN (-2550 2950);
DISPLAY INVISIBLE (-2550 2950);
FORCEPROP 1 LAST OFFPAGE TRUE
J 0
(-2175 2925);
DISPLAY 0.872340 (-2175 2925);
PAINT GREEN (-2175 2925);
DISPLAY INVISIBLE (-2175 2925);
FORCEADD OFFPAGE..2
(-2500 3100);
FORCEPROP 2 LAST $XR0 145 
J 0
(-2311 3100);
DISPLAY 0.638298 (-2311 3100);
PAINT MONO (-2311 3100);
FORCEPROP 2 LAST CDS_LIB mstr_standard
J 0
(-2500 3100);
PAINT MONO (-2500 3100);
DISPLAY INVISIBLE (-2500 3100);
FORCEPROP 2 LAST PATH I52
J 0
(-2325 3175);
DISPLAY 1.021277 (-2325 3175);
PAINT ORANGE (-2325 3175);
DISPLAY INVISIBLE (-2325 3175);
FORCEPROP 1 LAST OFFPAGE TRUE
J 0
(-2175 2975);
DISPLAY 0.872340 (-2175 2975);
PAINT GREEN (-2175 2975);
DISPLAY INVISIBLE (-2175 2975);
FORCEPROP 1 LAST COMMENT_BODY TRUE
J 0
(-2545 3005);
DISPLAY 0.872340 (-2545 3005);
PAINT GREEN (-2545 3005);
DISPLAY INVISIBLE (-2545 3005);
FORCEADD P3V3..1
(-3700 1375);
FORCEPROP 3 LASTPIN (-3700 1325) SIG_NAME P3V3\g
J 0
(-3690 1335);
DISPLAY 0.659574 (-3690 1335);
PAINT MONO (-3690 1335);
DISPLAY INVISIBLE (-3690 1335);
FORCEPROP 2 LAST CDS_LIB mstr_symbols
J 0
(-3700 1375);
PAINT ORANGE (-3700 1375);
DISPLAY INVISIBLE (-3700 1375);
FORCEPROP 1 LAST PATH I9
J 0
(-3655 1377);
DISPLAY 0.340426 (-3655 1377);
PAINT GREEN (-3655 1377);
DISPLAY INVISIBLE (-3655 1377);
FORCEPROP 1 LAST HDL_POWER P3V3
J 0
(-4025 1250);
DISPLAY 0.872340 (-4025 1250);
PAINT ORANGE (-4025 1250);
DISPLAY INVISIBLE (-4025 1250);
FORCEPROP 1 LAST BODY_TYPE PLUMBING
J 0
(-3745 1332);
DISPLAY 0.340426 (-3745 1332);
PAINT GREEN (-3745 1332);
DISPLAY INVISIBLE (-3745 1332);
FORCEPROP 1 LAST SIZE 1B
J 0
(-3655 1397);
DISPLAY 0.340426 (-3655 1397);
PAINT GREEN (-3655 1397);
DISPLAY INVISIBLE (-3655 1397);
FORCEPROP 1 LAST VOLTAGE 3.3V
J 0
(-3745 1332);
DISPLAY 0.340426 (-3745 1332);
PAINT SKYBLUE (-3745 1332);
DISPLAY INVISIBLE (-3745 1332);
FORCEADD CAD_NOTE..1
(-2300 2100);
FORCEPROP 0 LAST L2 TO IC
J 0
(-2450 1900);
DISPLAY 0.617021 (-2450 1900);
PAINT WHITE (-2450 1900);
FORCEPROP 0 LAST L1 PLACE CAP CLOSE
J 0
(-2450 1975);
DISPLAY 0.617021 (-2450 1975);
PAINT WHITE (-2450 1975);
FORCEPROP 1 LAST COMMENT_BODY TRUE
J 0
(-2275 2200);
DISPLAY 1.361702 (-2275 2200);
PAINT WHITE (-2275 2200);
DISPLAY INVISIBLE (-2275 2200);
FORCEPROP 2 LAST CDS_LIB mstr_symbols
J 0
(-2300 2100);
PAINT ORANGE (-2300 2100);
DISPLAY INVISIBLE (-2300 2100);
FORCEADD CAD_NOTE..1
(-3225 1325);
FORCEPROP 0 LAST L1 PLACE CAP CLOSE
J 0
(-3375 1200);
DISPLAY 0.617021 (-3375 1200);
PAINT WHITE (-3375 1200);
FORCEPROP 0 LAST L2 TO IC
J 0
(-3375 1125);
DISPLAY 0.617021 (-3375 1125);
PAINT WHITE (-3375 1125);
FORCEPROP 2 LAST CDS_LIB mstr_symbols
J 0
(-3225 1325);
PAINT ORANGE (-3225 1325);
DISPLAY INVISIBLE (-3225 1325);
FORCEPROP 1 LAST COMMENT_BODY TRUE
J 0
(-3200 1425);
DISPLAY 1.361702 (-3200 1425);
PAINT WHITE (-3200 1425);
DISPLAY INVISIBLE (-3200 1425);
FORCEADD DESIGN_NOTE..1
(-4000 3000);
FORCEPROP 1 LAST COMMENT_BODY TRUE
J 0
(-3975 3100);
DISPLAY 0.978723 (-3975 3100);
PAINT ORANGE (-3975 3100);
DISPLAY INVISIBLE (-3975 3100);
FORCEPROP 2 LAST CDS_LIB mstr_symbols
J 0
(-4000 3000);
PAINT ORANGE (-4000 3000);
DISPLAY INVISIBLE (-4000 3000);
FORCEADD INTEL_CORP_BPAGE..1
(0 0);
FORCEPROP 1 LAST CDS_CON_LAST_MODIFIED Fri Jun 16 17:49:30 2017
J 0
(-1425 325);
PAINT ORANGE (-1425 325);
DISPLAY INVISIBLE (-1425 325);
FORCEPROP 1 LAST CUSTOM_TXT_CDS <CURRENT_DESIGN_SHEET> OF <TOTAL_DESIGN_SHEETS>
J 0
(-500 25);
PAINT ORANGE (-500 25);
FORCEPROP 1 LAST CUSTOM_TXT_CDS <CON_LAST_MODIFIED>
J 0
(-4000 100);
PAINT ORANGE (-4000 100);
FORCEPROP 2 LAST CUSTOM_TXT_CDS <XR_PAGE_TITLE>
J 0
(-7890 5250);
DISPLAY 0.638298 (-7890 5250);
PAINT PINK (-7890 5250);
DISPLAY INVISIBLE (-7890 5250);
FORCEPROP 1 LAST SCH_TITLE CPU0 HOT PLUG AND M.2 RESET CIRCUIT
J 0
(-7950 50);
DISPLAY 2.468085 (-7950 50);
PAINT ORANGE (-7950 50);
FORCEPROP 2 LAST CDS_LIB mstr_symbols
J 0
(0 0);
PAINT MONO (0 0);
DISPLAY INVISIBLE (0 0);
FORCEPROP 1 LAST COMMENT_BODY TRUE
J 0
(12 12);
DISPLAY 0.468085 (12 12);
PAINT GREEN (12 12);
DISPLAY INVISIBLE (12 12);
FORCEPROP 2 LAST PAGE_BORDER TRUE
J 0
(-7890 5250);
DISPLAY 0.638298 (-7890 5250);
PAINT PINK (-7890 5250);
DISPLAY INVISIBLE (-7890 5250);
FORCEPROP 2 LAST CDS_XR_PAGE_TITLE CR-248 : @BASEBOARD_FAB2_LIB.BASEBOARD_FAB2(SCH_1):PAGE248
J 0
(-7890 5250);
DISPLAY 0.638298 (-7890 5250);
PAINT PINK (-7890 5250);
DISPLAY INVISIBLE (-7890 5250);
FORCEADD CAD_NOTE..1
(-3975 4775);
FORCEPROP 1 LAST COMMENT_BODY TRUE
J 0
(-3950 4875);
DISPLAY 1.319149 (-3950 4875);
PAINT WHITE (-3950 4875);
DISPLAY INVISIBLE (-3950 4875);
FORCEPROP 2 LAST CDS_LIB mstr_symbols
J 0
(-3975 4775);
PAINT MONO (-3975 4775);
DISPLAY INVISIBLE (-3975 4775);
FORCEADD CAD_NOTE..1
(-6300 3300);
FORCEPROP 1 LAST COMMENT_BODY TRUE
J 0
(-6275 3400);
DISPLAY 1.319149 (-6275 3400);
PAINT WHITE (-6275 3400);
DISPLAY INVISIBLE (-6275 3400);
FORCEPROP 2 LAST CDS_LIB mstr_symbols
J 0
(-6300 3300);
PAINT MONO (-6300 3300);
DISPLAY INVISIBLE (-6300 3300);
WIRE 16 -1 (-2750 1925)(-2750 1875);
WIRE 16 -1 (-2750 2175)(-2750 2125);
WIRE 16 -1 (-3700 1075)(-3700 1025);
WIRE 16 -1 (-4200 3950)(-4200 3875);
WIRE 16 -1 (-3525 3875)(-3525 3950);
WIRE 16 -1 (-2925 4125)(-2925 4225);
WIRE 16 -1 (-2925 4125)(-3000 4125);
WIRE 16 -1 (-2850 4125)(-2925 4125);
WIRE 16 -1 (-2850 3975)(-2850 4125);
WIRE 16 -1 (-3000 4125)(-3000 3975);
WIRE 16 -1 (-3450 4325)(-3450 4225);
WIRE 16 -1 (-3350 4225)(-3450 4225);
WIRE 16 -1 (-3450 4225)(-3525 4225);
WIRE 16 -1 (-3525 4225)(-3525 4150);
WIRE 16 -1 (-3350 3575)(-3350 4225);
WIRE 16 -1 (-3600 3575)(-3350 3575);
WIRE 16 -1 (-4275 4325)(-4275 4225);
WIRE 16 -1 (-4350 4225)(-4275 4225);
WIRE 16 -1 (-4275 4225)(-4200 4225);
WIRE 16 -1 (-4200 4225)(-4200 4150);
WIRE 16 -1 (-4350 3575)(-4350 4225);
WIRE 16 -1 (-4250 3575)(-4350 3575);
WIRE 16 -1 (-4700 4100)(-4700 4200);
WIRE 16 -1 (-4600 4100)(-4700 4100);
WIRE 16 -1 (-4700 4100)(-4750 4100);
WIRE 16 -1 (-4750 3975)(-4750 4100);
WIRE 16 -1 (-4600 3975)(-4600 4100);
WIRE 16 -1 (-4300 3425)(-4300 3375);
WIRE 16 -1 (-4250 3425)(-4300 3425);
WIRE 16 -1 (-3700 1325)(-3700 1275);
WIRE 3 2175 (-7525 4925)(-500 4925);
WIRE 3 2175 (-500 2800)(-500 4925);
WIRE 3 2175 (-7525 2800)(-7525 4925);
WIRE 3 2175 (-7525 2800)(-500 2800);
WIRE 3 2175 (-5775 850)(-2000 850);
WIRE 3 2175 (-2000 850)(-2000 2350);
WIRE 3 2175 (-5775 850)(-5775 2350);
WIRE 3 2175 (-5775 2350)(-2000 2350);
WIRE 16 682 (-6500 3750)(-6500 3050);
WIRE 16 682 (-5500 3750)(-6500 3750);
WIRE 16 682 (-6500 3050)(-5500 3050);
WIRE 16 682 (-5500 3050)(-5500 3750);
WIRE 16 -1 (-1350 3475)(-2100 3475);
FORCEPROP 0 LAST SIG_NAME SMB_PEHPCPU0_STBY_LVC3_SDA
J 0
(-2035 3485);
DISPLAY 0.617021 (-2035 3485);
PAINT ORANGE (-2035 3485);
WIRE 16 -1 (-6350 3525)(-7150 3525);
FORCEPROP 2 LAST SIG_NAME SMB_CPU0_PE_HP_GTL_SCL
J 0
(-7125 3535);
DISPLAY 0.617021 (-7125 3535);
PAINT ORANGE (-7125 3535);
WIRE 3 682 (-2800 2950)(-2050 2950);
WIRE 3 682 (-2050 2950)(-2050 3200);
WIRE 3 682 (-2800 3200)(-2800 2950);
WIRE 3 682 (-2800 3200)(-2050 3200);
WIRE 16 -1 (-3025 1625)(-2375 1625);
FORCEPROP 0 LAST SIG_NAME RST_PCIE_M2_DEV_IC_N
J 0
(-2925 1635);
DISPLAY 0.617021 (-2925 1635);
PAINT ORANGE (-2925 1635);
WIRE 16 -1 (-2350 3525)(-1325 3525);
FORCEPROP 0 LAST SIG_NAME SMB_PEHPCPU0_STBY_LVC3_SCL
J 0
(-2035 3535);
DISPLAY 0.617021 (-2035 3535);
PAINT ORANGE (-2035 3535);
WIRE 16 -1 (-3600 3475)(-2850 3475);
FORCEPROP 0 LAST SIG_NAME SMB_PEHPCPU0_STBY_LVC3_R_SDA
J 0
(-3510 3485);
DISPLAY 0.617021 (-3510 3485);
PAINT ORANGE (-3510 3485);
WIRE 16 -1 (-2850 3775)(-2850 3475);
WIRE 16 -1 (-2700 3050)(-2550 3050);
WIRE 16 -1 (-2700 3475)(-2700 3050);
WIRE 16 -1 (-2850 3475)(-2700 3475);
WIRE 16 -1 (-2700 3475)(-2300 3475);
WIRE 16 -1 (-2650 3100)(-2550 3100);
WIRE 16 -1 (-2650 3525)(-2650 3100);
WIRE 16 -1 (-2650 3525)(-2550 3525);
WIRE 16 -1 (-3000 3525)(-3600 3525);
FORCEPROP 0 LAST SIG_NAME SMB_PEHPCPU0_STBY_LVC3_R_SCL
J 0
(-3510 3535);
DISPLAY 0.617021 (-3510 3535);
PAINT ORANGE (-3510 3535);
WIRE 16 -1 (-3000 3525)(-2650 3525);
WIRE 16 -1 (-3000 3775)(-3000 3525);
WIRE 16 -1 (-2925 3425)(-3600 3425);
FORCEPROP 2 LAST SIG_NAME TP_SMB_PEHPCPU0_EN
J 0
(-3500 3435);
DISPLAY 0.617021 (-3500 3435);
PAINT ORANGE (-3500 3435);
FORCEPROP 2 LASTPROP $XRERR UNIQUE?
J 0
(-2895 3425);
DISPLAY 0.638298 (-2895 3425);
PAINT MONO (-2895 3425);
DISPLAY INVISIBLE (-2895 3425);
WIRE 16 -1 (-4600 3475)(-5800 3475);
FORCEPROP 2 LAST SIG_NAME SMB_CPU0_PE_HP_GTL_R_SDA
J 0
(-5450 3485);
DISPLAY 0.617021 (-5450 3485);
PAINT ORANGE (-5450 3485);
FORCEPROP 2 LASTPROP $XRERR UNIQUE?
J 0
(-5690 3485);
DISPLAY 0.638298 (-5690 3485);
PAINT MONO (-5690 3485);
DISPLAY INVISIBLE (-5690 3485);
WIRE 16 -1 (-4250 3475)(-4600 3475);
WIRE 16 -1 (-4600 3775)(-4600 3475);
WIRE 16 -1 (-4750 3775)(-4750 3525);
WIRE 16 -1 (-4250 3525)(-4750 3525);
WIRE 16 -1 (-6150 3525)(-4750 3525);
FORCEPROP 2 LAST SIG_NAME SMB_CPU0_PE_HP_GTL_R_SCL
J 0
(-5450 3535);
DISPLAY 0.617021 (-5450 3535);
PAINT ORANGE (-5450 3535);
FORCEPROP 2 LASTPROP $XRERR UNIQUE?
J 0
(-5690 3535);
DISPLAY 0.638298 (-5690 3535);
PAINT MONO (-5690 3535);
DISPLAY INVISIBLE (-5690 3535);
WIRE 16 -1 (-7150 3475)(-6000 3475);
FORCEPROP 2 LAST SIG_NAME SMB_CPU0_PE_HP_GTL_SDA
J 0
(-7125 3485);
DISPLAY 0.617021 (-7125 3485);
PAINT ORANGE (-7125 3485);
WIRE 16 -1 (-3850 1575)(-3325 1575);
FORCEPROP 0 LAST SIG_NAME RST_PCIE_M2_DEV_AND
J 0
(-3825 1585);
DISPLAY 0.617021 (-3825 1585);
PAINT ORANGE (-3825 1585);
FORCEPROP 2 LASTPROP $XRERR UNIQUE?
J 0
(-4065 1585);
DISPLAY 0.638298 (-4065 1585);
PAINT MONO (-4065 1585);
DISPLAY INVISIBLE (-4065 1585);
WIRE 16 -1 (-3850 1275)(-3850 1575);
WIRE 16 -1 (-3900 1275)(-3850 1275);
WIRE 16 -1 (-3325 1675)(-3900 1675);
FORCEPROP 0 LAST SIG_NAME RST_PCIE_M2_DEV_N
J 0
(-3825 1685);
DISPLAY 0.617021 (-3825 1685);
PAINT ORANGE (-3825 1685);
WIRE 16 -1 (-4200 1325)(-5200 1325);
FORCEPROP 2 LAST SIG_NAME PWRGD_P12V_HSC_DLY
J 0
(-5135 1335);
DISPLAY 1.021277 (-5135 1335);
PAINT ORANGE (-5135 1335);
WIRE 16 -1 (-4200 1225)(-5200 1225);
FORCEPROP 2 LAST SIG_NAME PWRGD_P3V3
J 0
(-5135 1235);
DISPLAY 1.021277 (-5135 1235);
PAINT ORANGE (-5135 1235);
DOT 1 (-3450 4225);
DOT 1 (-4750 3525);
DOT 1 (-4275 4225);
DOT 1 (-2925 4125);
DOT 1 (-4600 3475);
DOT 1 (-2850 3475);
DOT 1 (-4700 4100);
DOT 1 (-2700 3475);
DOT 1 (-3000 3525);
DOT 1 (-2650 3525);
FORCENOTE
TP FAB1  ADD FOR CPU0 HOT PLUG LEVER SHIFT
(-5137 2706) 0;
DISPLAY LEFT (-5137 2706);
DISPLAY 1.021277 (-5137 2706);
PAINT RED (-5137 2706);
FORCENOTE
TP FAB1 ADD FOR M.2 RESET CIRCUIT1204
(-4587 731) 0;
DISPLAY LEFT (-4587 731);
DISPLAY 1.021277 (-4587 731);
PAINT RED (-4587 731);
FORCENOTE
PLACE SEIRES RESISTORS NO MORE
(-6450 3200) 0;
DISPLAY LEFT (-6450 3200);
DISPLAY 0.808511 (-6450 3200);
PAINT PURPLE (-6450 3200);
FORCENOTE
THAN 3"  FROM CPU0
(-6450 3150) 0;
DISPLAY LEFT (-6450 3150);
DISPLAY 0.808511 (-6450 3150);
PAINT PURPLE (-6450 3150);
FORCENOTE
PE HP SMBUS ADDRESS 0X22
(-4175 2850) 0;
DISPLAY LEFT (-4175 2850);
DISPLAY 1.021277 (-4175 2850);
PAINT PURPLE (-4175 2850);
FORCENOTE
TP FAB1 CONNECT TO BMC SMB13 0121
(-2025 2975) 0;
DISPLAY LEFT (-2025 2975);
DISPLAY 1.021277 (-2025 2975);
PAINT RED (-2025 2975);
FORCENOTE
PLACE CAPS & PU RESISTORS NEAR TCA9517
(-4125 4625) 0;
DISPLAY LEFT (-4125 4625);
DISPLAY 1.021277 (-4125 4625);
PAINT PURPLE (-4125 4625);
QUIT
